(kicad_pcb
	(version 20260206)
	(generator "pcbnew")
	(generator_version "10.0")
	(general
		(thickness 1.6)
		(legacy_teardrops no)
	)
	(paper "A4")
	(title_block
		(title "v1-chassis-manager — T6M_CM_d_v01_1031_1645.brd")
		(comment 1 "Open CloudServer (Microsoft) / footprints 1054-1058 of 2512")
	)
	(layers
		(0 "F.Cu" signal "TOP")
		(4 "In1.Cu" signal "GND1")
		(6 "In2.Cu" signal "IN1")
		(8 "In3.Cu" signal "VCC1")
		(10 "In4.Cu" signal "VCC2")
		(12 "In5.Cu" signal "GND2")
		(14 "In6.Cu" signal "IN2")
		(16 "In7.Cu" signal "IN3")
		(18 "In8.Cu" signal "GND3")
		(2 "B.Cu" signal "BOTTOM")
		(9 "F.Adhes" user "F.Adhesive")
		(11 "B.Adhes" user "B.Adhesive")
		(13 "F.Paste" user "Package Geometry/Pastemask Top")
		(15 "B.Paste" user "Package Geometry/Pastemask Bottom")
		(5 "F.SilkS" user "Ref Des/Silkscreen Top")
		(7 "B.SilkS" user "Ref Des/Silkscreen Bottom")
		(1 "F.Mask" user "Board Geometry/Soldermask Top")
		(3 "B.Mask" user "Board Geometry/Soldermask Bottom")
		(17 "Dwgs.User" user "User.Drawings")
		(19 "Cmts.User" user "User.Comments")
		(21 "Eco1.User" user "User.Eco1")
		(23 "Eco2.User" user "User.Eco2")
		(25 "Edge.Cuts" user "Board Geometry/Outline")
		(27 "Margin" user)
		(31 "F.CrtYd" user "Package Geometry/Place Bound Top")
		(29 "B.CrtYd" user "Package Geometry/Place Bound Bottom")
		(35 "F.Fab" user "Ref Des/Assembly Top")
		(33 "B.Fab" user "Ref Des/Assembly Bottom")
	)
	(footprint ""
		(layer "F.Cu")
		(at 130.08864 -54.10835 90)
		(property "Reference" "C538"
			(at -1.27635 1.10363 90)
			(unlocked yes)
			(layer "F.SilkS")
			(effects
				(font
					(size 0.7874 0.5842)
					(thickness 0.1524)
				)
				(justify left)
			)
		)
		(property "Value" ""
			(at 0 0 90)
			(layer "F.Fab")
			(effects
				(font
					(size 1.27 1.27)
				)
			)
		)
		(duplicate_pad_numbers_are_jumpers no)
		(fp_line
			(start 0.7874 -0.4064)
			(end 0.7874 0.4064)
			(stroke
				(width 0.1524)
				(type default)
			)
			(layer "F.SilkS")
		)
		(fp_line
			(start -0.7874 -0.4064)
			(end 0.7874 -0.4064)
			(stroke
				(width 0.1524)
				(type default)
			)
			(layer "F.SilkS")
		)
		(fp_line
			(start 0 0.381)
			(end 0 -0.381)
			(stroke
				(width 0.1524)
				(type default)
			)
			(layer "F.SilkS")
		)
		(fp_line
			(start 0.7874 0.4064)
			(end -0.7874 0.4064)
			(stroke
				(width 0.1524)
				(type default)
			)
			(layer "F.SilkS")
		)
		(fp_line
			(start -0.7874 0.4064)
			(end -0.7874 -0.4064)
			(stroke
				(width 0.1524)
				(type default)
			)
			(layer "F.SilkS")
		)
		(fp_poly
			(pts
				(xy -0.5334 0.254) (xy -0.635 0.254) (xy -0.635 0.2286) (xy -0.635 -0.254) (xy -0.5334 -0.254) (xy -0.5334 -0.2794)
				(xy 0.5334 -0.2794) (xy 0.5334 -0.254) (xy 0.635 -0.254) (xy 0.635 0.254) (xy 0.5334 0.254) (xy 0.5334 0.2794)
				(xy -0.508 0.2794) (xy -0.5334 0.2794)
			)
			(stroke
				(width 0)
				(type default)
			)
			(fill no)
			(layer "F.CrtYd")
		)
		(pad "1" smd rect
			(at 0.40005 0 90)
			(size 0.4572 0.508)
			(layers "F.Cu" "F.Mask" "F.Paste")
			(net "P3V3_NODE1")
		)
		(pad "2" smd rect
			(at -0.40005 0 90)
			(size 0.4572 0.508)
			(layers "F.Cu" "F.Mask" "F.Paste")
			(net "GND")
		)
	)
	(footprint ""
		(layer "F.Cu")
		(at 51.906932 -98.929698 180)
		(property "Reference" "U9"
			(at 4.570222 -1.766824 0)
			(unlocked yes)
			(layer "F.SilkS")
			(effects
				(font
					(size 0.7874 0.5842)
					(thickness 0.1524)
				)
				(justify left)
			)
		)
		(property "Value" ""
			(at 0 0 180)
			(layer "F.Fab")
			(effects
				(font
					(size 1.27 1.27)
				)
			)
		)
		(duplicate_pad_numbers_are_jumpers no)
		(fp_line
			(start 4.040886 1.294892)
			(end 4.929886 1.294892)
			(stroke
				(width 0.1524)
				(type default)
			)
			(layer "F.SilkS")
		)
		(fp_line
			(start 3.81 3.024886)
			(end 3.81 2.25679)
			(stroke
				(width 0.1524)
				(type default)
			)
			(layer "F.SilkS")
		)
		(fp_line
			(start 3.81 -0.306832)
			(end 3.81 -1.074928)
			(stroke
				(width 0.1524)
				(type default)
			)
			(layer "F.SilkS")
		)
		(fp_line
			(start 3.81 -1.074928)
			(end 3.038602 -1.074928)
			(stroke
				(width 0.1524)
				(type default)
			)
			(layer "F.SilkS")
		)
		(fp_line
			(start 3.033776 3.024886)
			(end 3.81 3.024886)
			(stroke
				(width 0.1524)
				(type default)
			)
			(layer "F.SilkS")
		)
		(fp_line
			(start 1.429512 -1.350518)
			(end 1.429512 -1.858518)
			(stroke
				(width 0.1524)
				(type default)
			)
			(layer "F.SilkS")
		)
		(fp_line
			(start 0.778256 3.277108)
			(end 0.778256 3.785108)
			(stroke
				(width 0.1524)
				(type default)
			)
			(layer "F.SilkS")
		)
		(fp_line
			(start 0.483108 -1.074928)
			(end -0.290068 -1.074928)
			(stroke
				(width 0.1524)
				(type default)
			)
			(layer "F.SilkS")
		)
		(fp_line
			(start -0.290068 3.024886)
			(end 0.487934 3.024886)
			(stroke
				(width 0.1524)
				(type default)
			)
			(layer "F.SilkS")
		)
		(fp_line
			(start -0.290068 2.25044)
			(end -0.290068 3.024886)
			(stroke
				(width 0.1524)
				(type default)
			)
			(layer "F.SilkS")
		)
		(fp_line
			(start -0.290068 -1.074928)
			(end -0.290068 -0.309372)
			(stroke
				(width 0.1524)
				(type default)
			)
			(layer "F.SilkS")
		)
		(fp_poly
			(pts
				(xy -1.237742 -0.381) (xy -1.237742 0.381) (xy -0.475742 0)
			)
			(stroke
				(width 0)
				(type default)
			)
			(fill yes)
			(layer "F.SilkS")
		)
		(fp_poly
			(pts
				(xy 0.543814 3.141472) (xy 0.543814 3.024886) (xy -0.290068 3.024886) (xy -0.290068 2.191258) (xy -0.4064 2.191258)
				(xy -0.4064 -0.2413) (xy -0.290068 -0.2413) (xy -0.290068 -1.074928) (xy 0.543814 -1.074928) (xy 0.543814 -1.191514)
				(xy 2.976372 -1.191514) (xy 2.976372 -1.074928) (xy 3.81 -1.074928) (xy 3.81 -0.2413) (xy 3.926332 -0.2413)
				(xy 3.926332 2.191258) (xy 3.81 2.191258) (xy 3.81 3.024886) (xy 2.976372 3.024886) (xy 2.976372 3.141472)
			)
			(stroke
				(width 0)
				(type default)
			)
			(fill no)
			(layer "F.CrtYd")
		)
		(fp_line
			(start 4.040886 1.294892)
			(end 4.929886 1.294892)
			(stroke
				(width 0.1)
				(type default)
			)
			(layer "F.Fab")
		)
		(fp_line
			(start 3.81 3.024886)
			(end 3.81 -1.074928)
			(stroke
				(width 0.1)
				(type default)
			)
			(layer "F.Fab")
		)
		(fp_line
			(start 3.81 -1.074928)
			(end -0.290068 -1.074928)
			(stroke
				(width 0.1)
				(type default)
			)
			(layer "F.Fab")
		)
		(fp_line
			(start 1.429512 -1.350518)
			(end 1.429512 -1.858518)
			(stroke
				(width 0.1)
				(type default)
			)
			(layer "F.Fab")
		)
		(fp_line
			(start 0.778256 3.277108)
			(end 0.778256 3.785108)
			(stroke
				(width 0.1)
				(type default)
			)
			(layer "F.Fab")
		)
		(fp_line
			(start -0.290068 3.024886)
			(end 3.81 3.024886)
			(stroke
				(width 0.1)
				(type default)
			)
			(layer "F.Fab")
		)
		(fp_line
			(start -0.290068 -1.074928)
			(end -0.290068 3.024886)
			(stroke
				(width 0.1)
				(type default)
			)
			(layer "F.Fab")
		)
		(fp_poly
			(pts
				(xy -1.237742 -0.381) (xy -1.237742 0.381) (xy -0.475742 0)
			)
			(stroke
				(width 0)
				(type default)
			)
			(fill yes)
			(layer "F.Fab")
		)
		(fp_text user "12"
			(at 4.454652 -0.15621 0)
			(unlocked yes)
			(layer "F.SilkS")
			(effects
				(font
					(size 0.635 0.4064)
					(thickness 0.1524)
				)
			)
		)
		(fp_text user "9"
			(at 4.168902 2.082546 0)
			(unlocked yes)
			(layer "F.SilkS")
			(effects
				(font
					(size 0.635 0.4064)
					(thickness 0.1524)
				)
			)
		)
		(fp_text user "8"
			(at 3.358134 3.519678 0)
			(unlocked yes)
			(layer "F.SilkS")
			(effects
				(font
					(size 0.635 0.4064)
					(thickness 0.1524)
				)
			)
		)
		(fp_text user "13"
			(at 2.740914 -1.63957 0)
			(unlocked yes)
			(layer "F.SilkS")
			(effects
				(font
					(size 0.635 0.4064)
					(thickness 0.1524)
				)
			)
		)
		(fp_text user "16"
			(at 0.686308 -1.648714 0)
			(unlocked yes)
			(layer "F.SilkS")
			(effects
				(font
					(size 0.635 0.4064)
					(thickness 0.1524)
				)
			)
		)
		(fp_text user "5"
			(at 0.262636 3.556508 0)
			(unlocked yes)
			(layer "F.SilkS")
			(effects
				(font
					(size 0.635 0.4064)
					(thickness 0.1524)
				)
			)
		)
		(fp_text user "1"
			(at -0.589788 -0.693674 0)
			(unlocked yes)
			(layer "F.SilkS")
			(effects
				(font
					(size 0.635 0.4064)
					(thickness 0.1524)
				)
			)
		)
		(fp_text user "4"
			(at -0.686308 1.815338 0)
			(unlocked yes)
			(layer "F.SilkS")
			(effects
				(font
					(size 0.635 0.4064)
					(thickness 0.1524)
				)
			)
		)
		(fp_text user "12"
			(at 4.38023 -0.706882 270)
			(unlocked yes)
			(layer "F.Fab")
			(effects
				(font
					(size 0.635 0.4064)
					(thickness 0.000001)
				)
			)
		)
		(fp_text user "9"
			(at 4.309872 2.62128 270)
			(unlocked yes)
			(layer "F.Fab")
			(effects
				(font
					(size 0.635 0.4064)
					(thickness 0.000001)
				)
			)
		)
		(fp_text user "13"
			(at 3.370326 -1.593596 180)
			(unlocked yes)
			(layer "F.Fab")
			(effects
				(font
					(size 0.635 0.4064)
					(thickness 0.000001)
				)
			)
		)
		(fp_text user "8"
			(at 3.368802 3.51155 180)
			(unlocked yes)
			(layer "F.Fab")
			(effects
				(font
					(size 0.635 0.4064)
					(thickness 0.000001)
				)
			)
		)
		(fp_text user "5"
			(at 0.093472 3.53695 180)
			(unlocked yes)
			(layer "F.Fab")
			(effects
				(font
					(size 0.635 0.4064)
					(thickness 0.000001)
				)
			)
		)
		(fp_text user "16"
			(at 0.0127 -1.600454 180)
			(unlocked yes)
			(layer "F.Fab")
			(effects
				(font
					(size 0.635 0.4064)
					(thickness 0.000001)
				)
			)
		)
		(fp_text user "4"
			(at -0.736854 2.692146 270)
			(unlocked yes)
			(layer "F.Fab")
			(effects
				(font
					(size 0.635 0.4064)
					(thickness 0.000001)
				)
			)
		)
		(fp_text user "1"
			(at -0.769112 -0.660146 270)
			(unlocked yes)
			(layer "F.Fab")
			(effects
				(font
					(size 0.635 0.4064)
					(thickness 0.000001)
				)
			)
		)
		(pad "1" smd oval
			(at 0 0 270)
			(size 0.381 0.7112)
			(layers "F.Cu" "F.Mask" "F.Paste")
			(net "A_CPU0_NODE1_THERMDA")
		)
		(pad "2" smd oval
			(at 0 0.649986 270)
			(size 0.381 0.7112)
			(layers "F.Cu" "F.Mask" "F.Paste")
			(net "A_CPU0_NODE1_THERMDC")
		)
		(pad "3" smd oval
			(at 0 1.299972 270)
			(size 0.381 0.7112)
			(layers "F.Cu" "F.Mask" "F.Paste")
			(net "A_CPU1_NODE1_THERMDA")
		)
		(pad "4" smd oval
			(at 0 1.949958 270)
			(size 0.381 0.7112)
			(layers "F.Cu" "F.Mask" "F.Paste")
			(net "A_CPU1_NODE1_THERMDC")
		)
		(pad "5" smd oval
			(at 0.785114 2.735072 180)
			(size 0.381 0.7112)
			(layers "F.Cu" "F.Mask" "F.Paste")
			(net "PU_EMC1428_NODE1_TRIP")
		)
		(pad "6" smd oval
			(at 1.4351 2.735072 180)
			(size 0.381 0.7112)
			(layers "F.Cu" "F.Mask" "F.Paste")
			(net "PU_TEMP1_NODE1_SYS_SHDN_L")
		)
		(pad "7" smd oval
			(at 2.085086 2.735072 180)
			(size 0.381 0.7112)
			(layers "F.Cu" "F.Mask" "F.Paste")
			(net "SMB_TEMP1_NODE1_ALERT_R_L")
		)
		(pad "8" smd oval
			(at 2.735072 2.735072 180)
			(size 0.381 0.7112)
			(layers "F.Cu" "F.Mask" "F.Paste")
			(net "GND")
		)
		(pad "9" smd oval
			(at 3.519932 1.949958 270)
			(size 0.381 0.7112)
			(layers "F.Cu" "F.Mask" "F.Paste")
			(net "A_SOC_NODE1_THERMDC")
		)
		(pad "10" smd oval
			(at 3.519932 1.299972 270)
			(size 0.381 0.7112)
			(layers "F.Cu" "F.Mask" "F.Paste")
			(net "A_SOC_NODE1_THERMDA")
		)
		(pad "11" smd oval
			(at 3.519932 0.649986 270)
			(size 0.381 0.7112)
			(layers "F.Cu" "F.Mask" "F.Paste")
			(net "SMB_MUX_CPU_ICS_NODE1_DAT")
		)
		(pad "12" smd oval
			(at 3.519932 0 270)
			(size 0.381 0.7112)
			(layers "F.Cu" "F.Mask" "F.Paste")
			(net "SMB_MUX_CPU_ICS_NODE1_CLK")
		)
		(pad "13" smd oval
			(at 2.735072 -0.785114 180)
			(size 0.381 0.7112)
			(layers "F.Cu" "F.Mask" "F.Paste")
			(net "TP_TEMP1_NODE1_3")
		)
		(pad "14" smd oval
			(at 2.085086 -0.785114 180)
			(size 0.381 0.7112)
			(layers "F.Cu" "F.Mask" "F.Paste")
			(net "TP_TEMP1_NODE1_2")
		)
		(pad "15" smd oval
			(at 1.4351 -0.785114 180)
			(size 0.381 0.7112)
			(layers "F.Cu" "F.Mask" "F.Paste")
			(net "TP_TEMP1_NODE1_1")
		)
		(pad "16" smd oval
			(at 0.785114 -0.785114 180)
			(size 0.381 0.7112)
			(layers "F.Cu" "F.Mask" "F.Paste")
			(net "P3V3_NODE1")
		)
		(pad "TH" smd rect
			(at 1.759966 0.975106 180)
			(size 2.1082 2.1082)
			(layers "F.Cu" "F.Mask" "F.Paste")
			(net "GND")
		)
		(zone
			(layer "F.Cu")
			(hatch none 0.5)
			(connect_pads
				(clearance 0)
			)
			(min_thickness 0.25)
			(keepout
				(tracks allowed)
				(vias not_allowed)
				(pads allowed)
				(copperpour not_allowed)
				(footprints allowed)
			)
			(placement
				(enabled no)
				(sheetname "")
			)
			(fill
				(thermal_gap 0.5)
				(thermal_bridge_width 0.5)
				(island_removal_mode 0)
			)
			(polygon
				(pts
					(xy 51.500532 -101.25837) (xy 51.500532 -98.550984) (xy 51.251866 -98.550984) (xy 51.251866 -101.009704)
					(xy 49.042066 -101.009704) (xy 49.042066 -98.799904) (xy 51.237134 -98.799904) (xy 51.237134 -98.550984)
					(xy 48.7934 -98.550984) (xy 48.7934 -101.25837)
				)
			)
		)
		(zone
			(layer "F.Cu")
			(hatch none 0.5)
			(connect_pads
				(clearance 0)
			)
			(min_thickness 0.25)
			(keepout
				(tracks not_allowed)
				(vias allowed)
				(pads allowed)
				(copperpour not_allowed)
				(footprints allowed)
			)
			(placement
				(enabled no)
				(sheetname "")
			)
			(fill
				(thermal_gap 0.5)
				(thermal_bridge_width 0.5)
				(island_removal_mode 0)
			)
			(polygon
				(pts
					(xy 51.500532 -101.25837) (xy 51.500532 -98.550984) (xy 51.251866 -98.550984) (xy 51.251866 -101.009704)
					(xy 49.042066 -101.009704) (xy 49.042066 -98.799904) (xy 51.237134 -98.799904) (xy 51.237134 -98.550984)
					(xy 48.7934 -98.550984) (xy 48.7934 -101.25837)
				)
			)
		)
	)
	(footprint ""
		(layer "F.Cu")
		(at 45.532802 -145.829782 -90)
		(property "Reference" "R544"
			(at 0.88646 6.618732 90)
			(unlocked yes)
			(layer "F.SilkS")
			(effects
				(font
					(size 0.7874 0.5842)
					(thickness 0.1524)
				)
				(justify left)
			)
		)
		(property "Value" ""
			(at 0 0 270)
			(layer "F.Fab")
			(effects
				(font
					(size 1.27 1.27)
				)
			)
		)
		(duplicate_pad_numbers_are_jumpers no)
		(fp_line
			(start -0.7874 0.4064)
			(end -0.7874 -0.4064)
			(stroke
				(width 0.1524)
				(type default)
			)
			(layer "F.SilkS")
		)
		(fp_line
			(start 0.7874 0.4064)
			(end -0.7874 0.4064)
			(stroke
				(width 0.1524)
				(type default)
			)
			(layer "F.SilkS")
		)
		(fp_line
			(start -0.7874 -0.4064)
			(end 0.7874 -0.4064)
			(stroke
				(width 0.1524)
				(type default)
			)
			(layer "F.SilkS")
		)
		(fp_line
			(start 0.7874 -0.4064)
			(end 0.7874 0.4064)
			(stroke
				(width 0.1524)
				(type default)
			)
			(layer "F.SilkS")
		)
		(fp_poly
			(pts
				(xy -0.508 0.2794) (xy -0.508 0.2286) (xy -0.635 0.2286) (xy -0.635 -0.254) (xy -0.5334 -0.254)
				(xy -0.5334 -0.2794) (xy 0.5334 -0.2794) (xy 0.5334 -0.254) (xy 0.635 -0.254) (xy 0.635 0.254) (xy 0.5334 0.254)
				(xy 0.5334 0.2794)
			)
			(stroke
				(width 0)
				(type default)
			)
			(fill no)
			(layer "F.CrtYd")
		)
		(pad "1" smd rect
			(at 0.40005 0 270)
			(size 0.4572 0.508)
			(layers "F.Cu" "F.Mask" "F.Paste")
			(net "P3V3_NODE1")
		)
		(pad "2" smd rect
			(at -0.40005 0 270)
			(size 0.4572 0.508)
			(layers "F.Cu" "F.Mask" "F.Paste")
			(net "LAN1_NC_SI_TDX0")
		)
	)
	(footprint ""
		(layer "F.Cu")
		(at 129.1082 -50.8762 -90)
		(property "Reference" "R1161"
			(at -16.891 -30.83687 90)
			(unlocked yes)
			(layer "F.SilkS")
			(effects
				(font
					(size 0.7874 0.5842)
					(thickness 0.1524)
				)
				(justify left)
			)
		)
		(property "Value" ""
			(at 0 0 270)
			(layer "F.Fab")
			(effects
				(font
					(size 1.27 1.27)
				)
			)
		)
		(duplicate_pad_numbers_are_jumpers no)
		(fp_line
			(start -0.7874 0.4064)
			(end -0.7874 -0.4064)
			(stroke
				(width 0.1524)
				(type default)
			)
			(layer "F.SilkS")
		)
		(fp_line
			(start 0.7874 0.4064)
			(end -0.7874 0.4064)
			(stroke
				(width 0.1524)
				(type default)
			)
			(layer "F.SilkS")
		)
		(fp_line
			(start -0.7874 -0.4064)
			(end 0.7874 -0.4064)
			(stroke
				(width 0.1524)
				(type default)
			)
			(layer "F.SilkS")
		)
		(fp_line
			(start 0.7874 -0.4064)
			(end 0.7874 0.4064)
			(stroke
				(width 0.1524)
				(type default)
			)
			(layer "F.SilkS")
		)
		(fp_poly
			(pts
				(xy -0.508 0.2794) (xy -0.508 0.2286) (xy -0.635 0.2286) (xy -0.635 -0.254) (xy -0.5334 -0.254)
				(xy -0.5334 -0.2794) (xy 0.5334 -0.2794) (xy 0.5334 -0.254) (xy 0.635 -0.254) (xy 0.635 0.254) (xy 0.5334 0.254)
				(xy 0.5334 0.2794)
			)
			(stroke
				(width 0)
				(type default)
			)
			(fill no)
			(layer "F.CrtYd")
		)
		(pad "1" smd rect
			(at 0.40005 0 270)
			(size 0.4572 0.508)
			(layers "F.Cu" "F.Mask" "F.Paste")
			(net "UART_TX_P4_R")
		)
		(pad "2" smd rect
			(at -0.40005 0 270)
			(size 0.4572 0.508)
			(layers "F.Cu" "F.Mask" "F.Paste")
			(net "UART_TX_P4_BUF")
		)
	)
	(footprint ""
		(layer "F.Cu")
		(at 57.38876 -185.205624 90)
		(property "Reference" "C712"
			(at 4.006088 -0.154178 90)
			(unlocked yes)
			(layer "F.SilkS")
			(effects
				(font
					(size 0.7874 0.5842)
					(thickness 0.1524)
				)
				(justify left)
			)
		)
		(property "Value" ""
			(at 0 0 90)
			(layer "F.Fab")
			(effects
				(font
					(size 1.27 1.27)
				)
			)
		)
		(duplicate_pad_numbers_are_jumpers no)
		(fp_line
			(start 0.7874 -0.4064)
			(end 0.7874 0.4064)
			(stroke
				(width 0.1524)
				(type default)
			)
			(layer "F.SilkS")
		)
		(fp_line
			(start -0.7874 -0.4064)
			(end 0.7874 -0.4064)
			(stroke
				(width 0.1524)
				(type default)
			)
			(layer "F.SilkS")
		)
		(fp_line
			(start 0 0.381)
			(end 0 -0.381)
			(stroke
				(width 0.1524)
				(type default)
			)
			(layer "F.SilkS")
		)
		(fp_line
			(start 0.7874 0.4064)
			(end -0.7874 0.4064)
			(stroke
				(width 0.1524)
				(type default)
			)
			(layer "F.SilkS")
		)
		(fp_line
			(start -0.7874 0.4064)
			(end -0.7874 -0.4064)
			(stroke
				(width 0.1524)
				(type default)
			)
			(layer "F.SilkS")
		)
		(fp_poly
			(pts
				(xy -0.5334 0.254) (xy -0.635 0.254) (xy -0.635 0.2286) (xy -0.635 -0.254) (xy -0.5334 -0.254) (xy -0.5334 -0.2794)
				(xy 0.5334 -0.2794) (xy 0.5334 -0.254) (xy 0.635 -0.254) (xy 0.635 0.254) (xy 0.5334 0.254) (xy 0.5334 0.2794)
				(xy -0.508 0.2794) (xy -0.5334 0.2794)
			)
			(stroke
				(width 0)
				(type default)
			)
			(fill no)
			(layer "F.CrtYd")
		)
		(pad "1" smd rect
			(at 0.40005 0 90)
			(size 0.4572 0.508)
			(layers "F.Cu" "F.Mask" "F.Paste")
			(net "UART_T2_NODE4_RXD")
		)
		(pad "2" smd rect
			(at -0.40005 0 90)
			(size 0.4572 0.508)
			(layers "F.Cu" "F.Mask" "F.Paste")
			(net "GND")
		)
	)
)
